(kicad_pcb
	(version 20260206)
	(generator "pcbnew")
	(generator_version "10.0")
	(general
		(thickness 1.6)
		(legacy_teardrops no)
	)
	(paper "A4")
	(title_block
		(title "v1-chassis-manager — T6M_CM_d_v01_1031_1645.brd")
		(comment 1 "Open CloudServer (Microsoft) / footprints 642-652 of 2512")
	)
	(layers
		(0 "F.Cu" signal "TOP")
		(4 "In1.Cu" signal "GND1")
		(6 "In2.Cu" signal "IN1")
		(8 "In3.Cu" signal "VCC1")
		(10 "In4.Cu" signal "VCC2")
		(12 "In5.Cu" signal "GND2")
		(14 "In6.Cu" signal "IN2")
		(16 "In7.Cu" signal "IN3")
		(18 "In8.Cu" signal "GND3")
		(2 "B.Cu" signal "BOTTOM")
		(9 "F.Adhes" user "F.Adhesive")
		(11 "B.Adhes" user "B.Adhesive")
		(13 "F.Paste" user "Package Geometry/Pastemask Top")
		(15 "B.Paste" user "Package Geometry/Pastemask Bottom")
		(5 "F.SilkS" user "Ref Des/Silkscreen Top")
		(7 "B.SilkS" user "Ref Des/Silkscreen Bottom")
		(1 "F.Mask" user "Board Geometry/Soldermask Top")
		(3 "B.Mask" user "Board Geometry/Soldermask Bottom")
		(17 "Dwgs.User" user "User.Drawings")
		(19 "Cmts.User" user "User.Comments")
		(21 "Eco1.User" user "User.Eco1")
		(23 "Eco2.User" user "User.Eco2")
		(25 "Edge.Cuts" user "Board Geometry/Outline")
		(27 "Margin" user)
		(31 "F.CrtYd" user "Package Geometry/Place Bound Top")
		(29 "B.CrtYd" user "Package Geometry/Place Bound Bottom")
		(35 "F.Fab" user "Ref Des/Assembly Top")
		(33 "B.Fab" user "Ref Des/Assembly Bottom")
	)
	(footprint ""
		(layer "F.Cu")
		(at 45.339762 -185.552334 180)
		(property "Reference" "C604"
			(at -0.102616 3.141726 90)
			(unlocked yes)
			(layer "F.SilkS")
			(effects
				(font
					(size 0.7874 0.5842)
					(thickness 0.1524)
				)
				(justify left)
			)
		)
		(property "Value" ""
			(at 0 0 180)
			(layer "F.Fab")
			(effects
				(font
					(size 1.27 1.27)
				)
			)
		)
		(duplicate_pad_numbers_are_jumpers no)
		(fp_line
			(start 0.7874 0.4064)
			(end -0.7874 0.4064)
			(stroke
				(width 0.1524)
				(type default)
			)
			(layer "F.SilkS")
		)
		(fp_line
			(start 0.7874 -0.4064)
			(end 0.7874 0.4064)
			(stroke
				(width 0.1524)
				(type default)
			)
			(layer "F.SilkS")
		)
		(fp_line
			(start 0 0.381)
			(end 0 -0.381)
			(stroke
				(width 0.1524)
				(type default)
			)
			(layer "F.SilkS")
		)
		(fp_line
			(start -0.7874 0.4064)
			(end -0.7874 -0.4064)
			(stroke
				(width 0.1524)
				(type default)
			)
			(layer "F.SilkS")
		)
		(fp_line
			(start -0.7874 -0.4064)
			(end 0.7874 -0.4064)
			(stroke
				(width 0.1524)
				(type default)
			)
			(layer "F.SilkS")
		)
		(fp_poly
			(pts
				(xy -0.5334 0.254) (xy -0.635 0.254) (xy -0.635 0.2286) (xy -0.635 -0.254) (xy -0.5334 -0.254) (xy -0.5334 -0.2794)
				(xy 0.5334 -0.2794) (xy 0.5334 -0.254) (xy 0.635 -0.254) (xy 0.635 0.254) (xy 0.5334 0.254) (xy 0.5334 0.2794)
				(xy -0.508 0.2794) (xy -0.5334 0.2794)
			)
			(stroke
				(width 0)
				(type default)
			)
			(fill no)
			(layer "F.CrtYd")
		)
		(pad "1" smd rect
			(at 0.40005 0 180)
			(size 0.4572 0.508)
			(layers "F.Cu" "F.Mask" "F.Paste")
			(net "MATE_N")
		)
		(pad "2" smd rect
			(at -0.40005 0 180)
			(size 0.4572 0.508)
			(layers "F.Cu" "F.Mask" "F.Paste")
			(net "GND")
		)
	)
	(footprint ""
		(layer "F.Cu")
		(at 20.419314 -62.200536 90)
		(property "Reference" "R631"
			(at -1.28016 2.460498 90)
			(unlocked yes)
			(layer "F.SilkS")
			(effects
				(font
					(size 0.7874 0.5842)
					(thickness 0.1524)
				)
				(justify left)
			)
		)
		(property "Value" ""
			(at 0 0 90)
			(layer "F.Fab")
			(effects
				(font
					(size 1.27 1.27)
				)
			)
		)
		(duplicate_pad_numbers_are_jumpers no)
		(fp_line
			(start 0.7874 -0.4064)
			(end 0.7874 0.4064)
			(stroke
				(width 0.1524)
				(type default)
			)
			(layer "F.SilkS")
		)
		(fp_line
			(start -0.7874 -0.4064)
			(end 0.7874 -0.4064)
			(stroke
				(width 0.1524)
				(type default)
			)
			(layer "F.SilkS")
		)
		(fp_line
			(start 0.7874 0.4064)
			(end -0.7874 0.4064)
			(stroke
				(width 0.1524)
				(type default)
			)
			(layer "F.SilkS")
		)
		(fp_line
			(start -0.7874 0.4064)
			(end -0.7874 -0.4064)
			(stroke
				(width 0.1524)
				(type default)
			)
			(layer "F.SilkS")
		)
		(fp_poly
			(pts
				(xy -0.508 0.2794) (xy -0.508 0.2286) (xy -0.635 0.2286) (xy -0.635 -0.254) (xy -0.5334 -0.254)
				(xy -0.5334 -0.2794) (xy 0.5334 -0.2794) (xy 0.5334 -0.254) (xy 0.635 -0.254) (xy 0.635 0.254) (xy 0.5334 0.254)
				(xy 0.5334 0.2794)
			)
			(stroke
				(width 0)
				(type default)
			)
			(fill no)
			(layer "F.CrtYd")
		)
		(pad "1" smd rect
			(at 0.40005 0 90)
			(size 0.4572 0.508)
			(layers "F.Cu" "F.Mask" "F.Paste")
			(net "P3V3_NODE1")
		)
		(pad "2" smd rect
			(at -0.40005 0 90)
			(size 0.4572 0.508)
			(layers "F.Cu" "F.Mask" "F.Paste")
			(net "N21581283")
		)
	)
	(footprint ""
		(layer "F.Cu")
		(at 135.37057 -26.569416 -90)
		(property "Reference" "R1149"
			(at 5.325618 -0.255778 90)
			(unlocked yes)
			(layer "F.SilkS")
			(effects
				(font
					(size 0.7874 0.5842)
					(thickness 0.1524)
				)
				(justify left)
			)
		)
		(property "Value" ""
			(at 0 0 270)
			(layer "F.Fab")
			(effects
				(font
					(size 1.27 1.27)
				)
			)
		)
		(duplicate_pad_numbers_are_jumpers no)
		(fp_line
			(start -0.7874 0.4064)
			(end -0.7874 -0.4064)
			(stroke
				(width 0.1524)
				(type default)
			)
			(layer "F.SilkS")
		)
		(fp_line
			(start 0.7874 0.4064)
			(end -0.7874 0.4064)
			(stroke
				(width 0.1524)
				(type default)
			)
			(layer "F.SilkS")
		)
		(fp_line
			(start -0.7874 -0.4064)
			(end 0.7874 -0.4064)
			(stroke
				(width 0.1524)
				(type default)
			)
			(layer "F.SilkS")
		)
		(fp_line
			(start 0.7874 -0.4064)
			(end 0.7874 0.4064)
			(stroke
				(width 0.1524)
				(type default)
			)
			(layer "F.SilkS")
		)
		(fp_poly
			(pts
				(xy -0.508 0.2794) (xy -0.508 0.2286) (xy -0.635 0.2286) (xy -0.635 -0.254) (xy -0.5334 -0.254)
				(xy -0.5334 -0.2794) (xy 0.5334 -0.2794) (xy 0.5334 -0.254) (xy 0.635 -0.254) (xy 0.635 0.254) (xy 0.5334 0.254)
				(xy 0.5334 0.2794)
			)
			(stroke
				(width 0)
				(type default)
			)
			(fill no)
			(layer "F.CrtYd")
		)
		(pad "1" smd rect
			(at 0.40005 0 270)
			(size 0.4572 0.508)
			(layers "F.Cu" "F.Mask" "F.Paste")
			(net "P3V3_STB_NODE1")
		)
		(pad "2" smd rect
			(at -0.40005 0 270)
			(size 0.4572 0.508)
			(layers "F.Cu" "F.Mask" "F.Paste")
			(net "UART_RTS_P6_N")
		)
	)
	(footprint ""
		(layer "F.Cu")
		(at 25.000204 -26.800048)
		(property "Reference" "H9"
			(at 0 0 0)
			(layer "F.SilkS")
			(hide yes)
			(effects
				(font
					(size 1.27 1.27)
				)
			)
		)
		(property "Value" ""
			(at 0 0 0)
			(layer "F.Fab")
			(effects
				(font
					(size 1.27 1.27)
				)
			)
		)
		(duplicate_pad_numbers_are_jumpers no)
		(fp_poly
			(pts
				(arc
					(start 5.999734 5.050028)
					(mid 0 10.999933)
					(end -5.999734 5.050028)
				)
				(arc
					(start -5.999988 0.000254)
					(mid 0 -5.999988)
					(end 5.999988 0.000254)
				)
			)
			(stroke
				(width 0)
				(type default)
			)
			(fill no)
			(layer "B.CrtYd")
		)
		(fp_poly
			(pts
				(arc
					(start 5.999734 5.050028)
					(mid 0 10.999933)
					(end -5.999734 5.050028)
				)
				(arc
					(start -5.999988 0.000254)
					(mid 0 -5.999988)
					(end 5.999988 0.000254)
				)
			)
			(stroke
				(width 0)
				(type default)
			)
			(fill no)
			(layer "F.CrtYd")
		)
		(pad "" np_thru_hole circle
			(at 0 0)
			(size 3.6068 3.6068)
			(drill 3.6068)
			(layers "*.Cu" "*.Mask")
			(clearance 0.381)
			(thermal_gap 0.381)
		)
	)
	(footprint ""
		(layer "F.Cu")
		(at 64.864234 -152.974548)
		(property "Reference" "PC7"
			(at -32.356806 -5.850128 0)
			(unlocked yes)
			(layer "F.SilkS")
			(effects
				(font
					(size 0.7874 0.5842)
					(thickness 0.1524)
				)
				(justify left)
			)
		)
		(property "Value" ""
			(at 0 0 0)
			(layer "F.Fab")
			(effects
				(font
					(size 1.27 1.27)
				)
			)
		)
		(duplicate_pad_numbers_are_jumpers no)
		(fp_line
			(start -0.7874 -0.4064)
			(end 0.7874 -0.4064)
			(stroke
				(width 0.1524)
				(type default)
			)
			(layer "F.SilkS")
		)
		(fp_line
			(start -0.7874 0.4064)
			(end -0.7874 -0.4064)
			(stroke
				(width 0.1524)
				(type default)
			)
			(layer "F.SilkS")
		)
		(fp_line
			(start 0 0.381)
			(end 0 -0.381)
			(stroke
				(width 0.1524)
				(type default)
			)
			(layer "F.SilkS")
		)
		(fp_line
			(start 0.7874 -0.4064)
			(end 0.7874 0.4064)
			(stroke
				(width 0.1524)
				(type default)
			)
			(layer "F.SilkS")
		)
		(fp_line
			(start 0.7874 0.4064)
			(end -0.7874 0.4064)
			(stroke
				(width 0.1524)
				(type default)
			)
			(layer "F.SilkS")
		)
		(fp_poly
			(pts
				(xy -0.5334 0.254) (xy -0.635 0.254) (xy -0.635 0.2286) (xy -0.635 -0.254) (xy -0.5334 -0.254) (xy -0.5334 -0.2794)
				(xy 0.5334 -0.2794) (xy 0.5334 -0.254) (xy 0.635 -0.254) (xy 0.635 0.254) (xy 0.5334 0.254) (xy 0.5334 0.2794)
				(xy -0.508 0.2794) (xy -0.5334 0.2794)
			)
			(stroke
				(width 0)
				(type default)
			)
			(fill no)
			(layer "F.CrtYd")
		)
		(pad "1" smd rect
			(at 0.40005 0)
			(size 0.4572 0.508)
			(layers "F.Cu" "F.Mask" "F.Paste")
			(net "P5V_STB_NODE1")
		)
		(pad "2" smd rect
			(at -0.40005 0)
			(size 0.4572 0.508)
			(layers "F.Cu" "F.Mask" "F.Paste")
			(net "GND")
		)
	)
	(footprint ""
		(layer "F.Cu")
		(at 157.33776 -185.205624 -90)
		(property "Reference" "R823"
			(at -4.768088 -0.297942 90)
			(unlocked yes)
			(layer "F.SilkS")
			(effects
				(font
					(size 0.7874 0.5842)
					(thickness 0.1524)
				)
				(justify left)
			)
		)
		(property "Value" ""
			(at 0 0 270)
			(layer "F.Fab")
			(effects
				(font
					(size 1.27 1.27)
				)
			)
		)
		(duplicate_pad_numbers_are_jumpers no)
		(fp_line
			(start -0.7874 0.4064)
			(end -0.7874 -0.4064)
			(stroke
				(width 0.1524)
				(type default)
			)
			(layer "F.SilkS")
		)
		(fp_line
			(start 0.7874 0.4064)
			(end -0.7874 0.4064)
			(stroke
				(width 0.1524)
				(type default)
			)
			(layer "F.SilkS")
		)
		(fp_line
			(start -0.7874 -0.4064)
			(end 0.7874 -0.4064)
			(stroke
				(width 0.1524)
				(type default)
			)
			(layer "F.SilkS")
		)
		(fp_line
			(start 0.7874 -0.4064)
			(end 0.7874 0.4064)
			(stroke
				(width 0.1524)
				(type default)
			)
			(layer "F.SilkS")
		)
		(fp_poly
			(pts
				(xy -0.508 0.2794) (xy -0.508 0.2286) (xy -0.635 0.2286) (xy -0.635 -0.254) (xy -0.5334 -0.254)
				(xy -0.5334 -0.2794) (xy 0.5334 -0.2794) (xy 0.5334 -0.254) (xy 0.635 -0.254) (xy 0.635 0.254) (xy 0.5334 0.254)
				(xy 0.5334 0.2794)
			)
			(stroke
				(width 0)
				(type default)
			)
			(fill no)
			(layer "F.CrtYd")
		)
		(pad "1" smd rect
			(at 0.40005 0 270)
			(size 0.4572 0.508)
			(layers "F.Cu" "F.Mask" "F.Paste")
			(net "FAN2_TACH")
		)
		(pad "2" smd rect
			(at -0.40005 0 270)
			(size 0.4572 0.508)
			(layers "F.Cu" "F.Mask" "F.Paste")
			(net "FAN2_TACH_R")
		)
	)
	(footprint ""
		(layer "F.Cu")
		(at 150.478998 -142.88643 -90)
		(property "Reference" "R593"
			(at -1.435354 0.800354 90)
			(unlocked yes)
			(layer "F.SilkS")
			(effects
				(font
					(size 0.635 0.4064)
					(thickness 0.1524)
				)
				(justify left)
			)
		)
		(property "Value" ""
			(at 0 0 270)
			(layer "F.Fab")
			(effects
				(font
					(size 1.27 1.27)
				)
			)
		)
		(duplicate_pad_numbers_are_jumpers no)
		(fp_line
			(start -0.7874 0.4064)
			(end -0.7874 -0.4064)
			(stroke
				(width 0.1524)
				(type default)
			)
			(layer "F.SilkS")
		)
		(fp_line
			(start 0.7874 0.4064)
			(end -0.7874 0.4064)
			(stroke
				(width 0.1524)
				(type default)
			)
			(layer "F.SilkS")
		)
		(fp_line
			(start -0.7874 -0.4064)
			(end 0.7874 -0.4064)
			(stroke
				(width 0.1524)
				(type default)
			)
			(layer "F.SilkS")
		)
		(fp_line
			(start 0.7874 -0.4064)
			(end 0.7874 0.4064)
			(stroke
				(width 0.1524)
				(type default)
			)
			(layer "F.SilkS")
		)
		(fp_poly
			(pts
				(xy -0.508 0.2794) (xy -0.508 0.2286) (xy -0.635 0.2286) (xy -0.635 -0.254) (xy -0.5334 -0.254)
				(xy -0.5334 -0.2794) (xy 0.5334 -0.2794) (xy 0.5334 -0.254) (xy 0.635 -0.254) (xy 0.635 0.254) (xy 0.5334 0.254)
				(xy 0.5334 0.2794)
			)
			(stroke
				(width 0)
				(type default)
			)
			(fill no)
			(layer "F.CrtYd")
		)
		(pad "1" smd rect
			(at 0.40005 0 270)
			(size 0.4572 0.508)
			(layers "F.Cu" "F.Mask" "F.Paste")
			(net "SMB_PCH_SCL")
		)
		(pad "2" smd rect
			(at -0.40005 0 270)
			(size 0.4572 0.508)
			(layers "F.Cu" "F.Mask" "F.Paste")
			(net "SMB_LAN2_CLK")
		)
	)
	(footprint ""
		(layer "F.Cu")
		(at 150.649178 -73.937622 90)
		(property "Reference" "C332"
			(at -0.780034 2.370074 90)
			(unlocked yes)
			(layer "F.SilkS")
			(effects
				(font
					(size 0.7874 0.5842)
					(thickness 0.1524)
				)
				(justify left)
			)
		)
		(property "Value" ""
			(at 0 0 90)
			(layer "F.Fab")
			(effects
				(font
					(size 1.27 1.27)
				)
			)
		)
		(duplicate_pad_numbers_are_jumpers no)
		(fp_line
			(start 0.7874 -0.4064)
			(end 0.7874 0.4064)
			(stroke
				(width 0.1524)
				(type default)
			)
			(layer "F.SilkS")
		)
		(fp_line
			(start -0.7874 -0.4064)
			(end 0.7874 -0.4064)
			(stroke
				(width 0.1524)
				(type default)
			)
			(layer "F.SilkS")
		)
		(fp_line
			(start 0 0.381)
			(end 0 -0.381)
			(stroke
				(width 0.1524)
				(type default)
			)
			(layer "F.SilkS")
		)
		(fp_line
			(start 0.7874 0.4064)
			(end -0.7874 0.4064)
			(stroke
				(width 0.1524)
				(type default)
			)
			(layer "F.SilkS")
		)
		(fp_line
			(start -0.7874 0.4064)
			(end -0.7874 -0.4064)
			(stroke
				(width 0.1524)
				(type default)
			)
			(layer "F.SilkS")
		)
		(fp_poly
			(pts
				(xy -0.5334 0.254) (xy -0.635 0.254) (xy -0.635 0.2286) (xy -0.635 -0.254) (xy -0.5334 -0.254) (xy -0.5334 -0.2794)
				(xy 0.5334 -0.2794) (xy 0.5334 -0.254) (xy 0.635 -0.254) (xy 0.635 0.254) (xy 0.5334 0.254) (xy 0.5334 0.2794)
				(xy -0.508 0.2794) (xy -0.5334 0.2794)
			)
			(stroke
				(width 0)
				(type default)
			)
			(fill no)
			(layer "F.CrtYd")
		)
		(pad "1" smd rect
			(at 0.40005 0 90)
			(size 0.4572 0.508)
			(layers "F.Cu" "F.Mask" "F.Paste")
			(net "P2E_CPU_SATA_NODE1_RX_DN")
		)
		(pad "2" smd rect
			(at -0.40005 0 90)
			(size 0.4572 0.508)
			(layers "F.Cu" "F.Mask" "F.Paste")
			(net "P2E_CPU_SATA_NODE1_RX_C_DN")
		)
	)
	(footprint ""
		(layer "F.Cu")
		(at 114.046254 -61.255148)
		(property "Reference" "R229"
			(at 1.191768 1.859788 0)
			(unlocked yes)
			(layer "F.SilkS")
			(effects
				(font
					(size 0.7874 0.5842)
					(thickness 0.1524)
				)
				(justify left)
			)
		)
		(property "Value" ""
			(at 0 0 0)
			(layer "F.Fab")
			(effects
				(font
					(size 1.27 1.27)
				)
			)
		)
		(duplicate_pad_numbers_are_jumpers no)
		(fp_line
			(start -0.7874 -0.4064)
			(end 0.7874 -0.4064)
			(stroke
				(width 0.1524)
				(type default)
			)
			(layer "F.SilkS")
		)
		(fp_line
			(start -0.7874 0.4064)
			(end -0.7874 -0.4064)
			(stroke
				(width 0.1524)
				(type default)
			)
			(layer "F.SilkS")
		)
		(fp_line
			(start 0.7874 -0.4064)
			(end 0.7874 0.4064)
			(stroke
				(width 0.1524)
				(type default)
			)
			(layer "F.SilkS")
		)
		(fp_line
			(start 0.7874 0.4064)
			(end -0.7874 0.4064)
			(stroke
				(width 0.1524)
				(type default)
			)
			(layer "F.SilkS")
		)
		(fp_poly
			(pts
				(xy -0.508 0.2794) (xy -0.508 0.2286) (xy -0.635 0.2286) (xy -0.635 -0.254) (xy -0.5334 -0.254)
				(xy -0.5334 -0.2794) (xy 0.5334 -0.2794) (xy 0.5334 -0.254) (xy 0.635 -0.254) (xy 0.635 0.254) (xy 0.5334 0.254)
				(xy 0.5334 0.2794)
			)
			(stroke
				(width 0)
				(type default)
			)
			(fill no)
			(layer "F.CrtYd")
		)
		(pad "1" smd rect
			(at 0.40005 0)
			(size 0.4572 0.508)
			(layers "F.Cu" "F.Mask" "F.Paste")
			(net "GND")
		)
		(pad "2" smd rect
			(at -0.40005 0)
			(size 0.4572 0.508)
			(layers "F.Cu" "F.Mask" "F.Paste")
			(net "XDP_SOC_CPU_NODE1_TRST_L")
		)
	)
	(footprint ""
		(layer "F.Cu")
		(at 105.075228 -160.489138)
		(property "Reference" "R1129"
			(at 86.399624 70.566788 0)
			(unlocked yes)
			(layer "F.SilkS")
			(effects
				(font
					(size 0.7874 0.5842)
					(thickness 0.1524)
				)
				(justify left)
			)
		)
		(property "Value" ""
			(at 0 0 0)
			(layer "F.Fab")
			(effects
				(font
					(size 1.27 1.27)
				)
			)
		)
		(duplicate_pad_numbers_are_jumpers no)
		(fp_line
			(start -1.905 -0.8636)
			(end 1.905 -0.8636)
			(stroke
				(width 0.1524)
				(type default)
			)
			(layer "F.SilkS")
		)
		(fp_line
			(start -1.905 0.8636)
			(end -1.905 -0.8636)
			(stroke
				(width 0.1524)
				(type default)
			)
			(layer "F.SilkS")
		)
		(fp_line
			(start 1.905 -0.8636)
			(end 1.905 0.8636)
			(stroke
				(width 0.1524)
				(type default)
			)
			(layer "F.SilkS")
		)
		(fp_line
			(start 1.905 0.8636)
			(end -1.905 0.8636)
			(stroke
				(width 0.1524)
				(type default)
			)
			(layer "F.SilkS")
		)
		(fp_poly
			(pts
				(xy 1.524 0.6858) (xy 1.524 -0.6858) (xy 1.524 -0.7366) (xy -1.524 -0.7366) (xy -1.524 -0.6858)
				(xy -1.524 0.6858) (xy -1.524 0.7366) (xy 1.524 0.7366)
			)
			(stroke
				(width 0)
				(type default)
			)
			(fill no)
			(layer "F.CrtYd")
		)
		(pad "1" smd rect
			(at 0.94996 0)
			(size 1.1176 1.3716)
			(layers "F.Cu" "F.Mask" "F.Paste")
			(net "P12V_AUX")
		)
		(pad "2" smd rect
			(at -0.94996 0)
			(size 1.1176 1.3716)
			(layers "F.Cu" "F.Mask" "F.Paste")
			(net "N52411102")
		)
	)
	(footprint ""
		(layer "F.Cu")
		(at 139.93876 -185.205624 -90)
		(property "Reference" "R876"
			(at -4.768088 0.474472 90)
			(unlocked yes)
			(layer "F.SilkS")
			(effects
				(font
					(size 0.7874 0.5842)
					(thickness 0.1524)
				)
				(justify left)
			)
		)
		(property "Value" ""
			(at 0 0 270)
			(layer "F.Fab")
			(effects
				(font
					(size 1.27 1.27)
				)
			)
		)
		(duplicate_pad_numbers_are_jumpers no)
		(fp_line
			(start -0.7874 0.4064)
			(end -0.7874 -0.4064)
			(stroke
				(width 0.1524)
				(type default)
			)
			(layer "F.SilkS")
		)
		(fp_line
			(start 0.7874 0.4064)
			(end -0.7874 0.4064)
			(stroke
				(width 0.1524)
				(type default)
			)
			(layer "F.SilkS")
		)
		(fp_line
			(start -0.7874 -0.4064)
			(end 0.7874 -0.4064)
			(stroke
				(width 0.1524)
				(type default)
			)
			(layer "F.SilkS")
		)
		(fp_line
			(start 0.7874 -0.4064)
			(end 0.7874 0.4064)
			(stroke
				(width 0.1524)
				(type default)
			)
			(layer "F.SilkS")
		)
		(fp_poly
			(pts
				(xy -0.508 0.2794) (xy -0.508 0.2286) (xy -0.635 0.2286) (xy -0.635 -0.254) (xy -0.5334 -0.254)
				(xy -0.5334 -0.2794) (xy 0.5334 -0.2794) (xy 0.5334 -0.254) (xy 0.635 -0.254) (xy 0.635 0.254) (xy 0.5334 0.254)
				(xy 0.5334 0.2794)
			)
			(stroke
				(width 0)
				(type default)
			)
			(fill no)
			(layer "F.CrtYd")
		)
		(pad "1" smd rect
			(at 0.40005 0 270)
			(size 0.4572 0.508)
			(layers "F.Cu" "F.Mask" "F.Paste")
			(net "T10_NODE2_EN")
		)
		(pad "2" smd rect
			(at -0.40005 0 270)
			(size 0.4572 0.508)
			(layers "F.Cu" "F.Mask" "F.Paste")
			(net "T10_NODE2_EN_R")
		)
	)
)
